(kicad_pcb
	(version 20260206)
	(generator "pcbnew")
	(generator_version "10.0")
	(general
		(thickness 1.6)
		(legacy_teardrops no)
	)
	(paper "A4")
	(title_block
		(title "01162023_DA0F0TEBIF0_F0T_Expander_BD_F_brd_V02_OCP.brd")
		(comment 1 "Grand Teton / footprint 5622 of 9728 (PEX2), pads 836-956 of 2397")
	)
	(layers
		(0 "F.Cu" signal "TOP")
		(4 "In1.Cu" signal "GND")
		(6 "In2.Cu" signal "VCC")
		(8 "In3.Cu" signal "VCC1")
		(10 "In4.Cu" signal "GND1")
		(12 "In5.Cu" signal "IN1")
		(14 "In6.Cu" signal "GND2")
		(16 "In7.Cu" signal "IN2")
		(18 "In8.Cu" signal "GND3")
		(20 "In9.Cu" signal "IN3")
		(22 "In10.Cu" signal "GND4")
		(24 "In11.Cu" signal "IN4")
		(26 "In12.Cu" signal "GND5")
		(28 "In13.Cu" signal "IN5")
		(30 "In14.Cu" signal "GND6")
		(32 "In15.Cu" signal "IN6")
		(34 "In16.Cu" signal "GND7")
		(2 "B.Cu" signal "BOTTOM")
		(9 "F.Adhes" user "F.Adhesive")
		(11 "B.Adhes" user "B.Adhesive")
		(13 "F.Paste" user "Package Geometry/Pastemask Top")
		(15 "B.Paste" user "Package Geometry/Pastemask Bottom")
		(5 "F.SilkS" user "Ref Des/Silkscreen Top")
		(7 "B.SilkS" user "Ref Des/Silkscreen Bottom")
		(1 "F.Mask" user "Board Geometry/Soldermask Top")
		(3 "B.Mask" user "Board Geometry/Soldermask Bottom")
		(17 "Dwgs.User" user "User.Drawings")
		(19 "Cmts.User" user "User.Comments")
		(21 "Eco1.User" user "User.Eco1")
		(23 "Eco2.User" user "User.Eco2")
		(25 "Edge.Cuts" user "Board Geometry/Outline")
		(27 "Margin" user)
		(31 "F.CrtYd" user "Package Geometry/Place Bound Top")
		(29 "B.CrtYd" user "Package Geometry/Place Bound Bottom")
		(35 "F.Fab" user "Ref Des/Assembly Top")
		(33 "B.Fab" user "Ref Des/Assembly Bottom")
	)
	(footprint ""
		(layer "F.Cu")
		(at 291.84981 -295.89984)
		(property "Reference" "PEX2"
			(at -3.35153 35.56762 0)
			(unlocked yes)
			(layer "F.SilkS")
			(effects
				(font
					(size 2.032 1.524)
					(thickness 0.1524)
				)
				(justify left)
			)
		)
		(property "Value" ""
			(at 0 0 0)
			(layer "F.Fab")
			(effects
				(font
					(size 1.27 1.27)
				)
			)
		)
		(duplicate_pad_numbers_are_jumpers no)
		(pad "AU5" smd circle
			(at -18.999962 11.400028)
			(size 0.4572 0.4572)
			(layers "F.Cu" "F.Mask" "F.Paste")
			(net "GND")
		)
		(pad "AU6" smd circle
			(at -18.050002 11.400028)
			(size 0.4572 0.4572)
			(layers "F.Cu" "F.Mask" "F.Paste")
			(net "Net_1724")
		)
		(pad "AU7" smd circle
			(at -17.100042 11.400028)
			(size 0.4572 0.4572)
			(layers "F.Cu" "F.Mask" "F.Paste")
			(net "Net_1442")
		)
		(pad "AU8" smd circle
			(at -16.150082 11.400028)
			(size 0.4572 0.4572)
			(layers "F.Cu" "F.Mask" "F.Paste")
			(net "GND")
		)
		(pad "AU9" smd circle
			(at -15.200122 11.400028)
			(size 0.4572 0.4572)
			(layers "F.Cu" "F.Mask" "F.Paste")
			(net "GND")
		)
		(pad "AU10" smd circle
			(at -14.249908 11.400028)
			(size 0.4572 0.4572)
			(layers "F.Cu" "F.Mask" "F.Paste")
			(net "GND")
		)
		(pad "AU11" smd circle
			(at -13.299948 11.400028)
			(size 0.4572 0.4572)
			(layers "F.Cu" "F.Mask" "F.Paste")
			(net "GND")
		)
		(pad "AU12" smd circle
			(at -12.349988 11.400028)
			(size 0.4572 0.4572)
			(layers "F.Cu" "F.Mask" "F.Paste")
			(net "GND")
		)
		(pad "AU13" smd circle
			(at -11.400028 11.400028)
			(size 0.4572 0.4572)
			(layers "F.Cu" "F.Mask" "F.Paste")
			(net "GND")
		)
		(pad "AU14" smd circle
			(at -10.450068 11.400028)
			(size 0.4572 0.4572)
			(layers "F.Cu" "F.Mask" "F.Paste")
			(net "GND")
		)
		(pad "AU15" smd circle
			(at -9.500108 11.400028)
			(size 0.4572 0.4572)
			(layers "F.Cu" "F.Mask" "F.Paste")
			(net "GND")
		)
		(pad "AU16" smd circle
			(at -8.549894 11.400028)
			(size 0.4572 0.4572)
			(layers "F.Cu" "F.Mask" "F.Paste")
			(net "GND")
		)
		(pad "AU17" smd circle
			(at -7.599934 11.400028)
			(size 0.4572 0.4572)
			(layers "F.Cu" "F.Mask" "F.Paste")
			(net "GND")
		)
		(pad "AU18" smd circle
			(at -6.649974 11.400028)
			(size 0.4572 0.4572)
			(layers "F.Cu" "F.Mask" "F.Paste")
			(net "GND")
		)
		(pad "AU19" smd circle
			(at -5.700014 11.400028)
			(size 0.4572 0.4572)
			(layers "F.Cu" "F.Mask" "F.Paste")
			(net "GND")
		)
		(pad "AU20" smd circle
			(at -4.750054 11.400028)
			(size 0.4572 0.4572)
			(layers "F.Cu" "F.Mask" "F.Paste")
			(net "GND")
		)
		(pad "AU21" smd circle
			(at -3.800094 11.400028)
			(size 0.4572 0.4572)
			(layers "F.Cu" "F.Mask" "F.Paste")
			(net "GND")
		)
		(pad "AU22" smd circle
			(at -2.84988 11.400028)
			(size 0.4572 0.4572)
			(layers "F.Cu" "F.Mask" "F.Paste")
			(net "GND")
		)
		(pad "AU23" smd circle
			(at -1.89992 11.400028)
			(size 0.4572 0.4572)
			(layers "F.Cu" "F.Mask" "F.Paste")
			(net "GND")
		)
		(pad "AU24" smd circle
			(at -0.94996 11.400028)
			(size 0.4572 0.4572)
			(layers "F.Cu" "F.Mask" "F.Paste")
			(net "GND")
		)
		(pad "AU25" smd circle
			(at 0 11.400028)
			(size 0.4572 0.4572)
			(layers "F.Cu" "F.Mask" "F.Paste")
			(net "GND")
		)
		(pad "AU26" smd circle
			(at 0.94996 11.400028)
			(size 0.4572 0.4572)
			(layers "F.Cu" "F.Mask" "F.Paste")
			(net "GND")
		)
		(pad "AU27" smd circle
			(at 1.89992 11.400028)
			(size 0.4572 0.4572)
			(layers "F.Cu" "F.Mask" "F.Paste")
			(net "GND")
		)
		(pad "AU28" smd circle
			(at 2.84988 11.400028)
			(size 0.4572 0.4572)
			(layers "F.Cu" "F.Mask" "F.Paste")
			(net "GND")
		)
		(pad "AU29" smd circle
			(at 3.800094 11.400028)
			(size 0.4572 0.4572)
			(layers "F.Cu" "F.Mask" "F.Paste")
			(net "GND")
		)
		(pad "AU30" smd circle
			(at 4.750054 11.400028)
			(size 0.4572 0.4572)
			(layers "F.Cu" "F.Mask" "F.Paste")
			(net "GND")
		)
		(pad "AU31" smd circle
			(at 5.700014 11.400028)
			(size 0.4572 0.4572)
			(layers "F.Cu" "F.Mask" "F.Paste")
			(net "GND")
		)
		(pad "AU32" smd circle
			(at 6.649974 11.400028)
			(size 0.4572 0.4572)
			(layers "F.Cu" "F.Mask" "F.Paste")
			(net "GND")
		)
		(pad "AU33" smd circle
			(at 7.599934 11.400028)
			(size 0.4572 0.4572)
			(layers "F.Cu" "F.Mask" "F.Paste")
			(net "GND")
		)
		(pad "AU34" smd circle
			(at 8.549894 11.400028)
			(size 0.4572 0.4572)
			(layers "F.Cu" "F.Mask" "F.Paste")
			(net "GND")
		)
		(pad "AU35" smd circle
			(at 9.500108 11.400028)
			(size 0.4572 0.4572)
			(layers "F.Cu" "F.Mask" "F.Paste")
			(net "GND")
		)
		(pad "AU36" smd circle
			(at 10.450068 11.400028)
			(size 0.4572 0.4572)
			(layers "F.Cu" "F.Mask" "F.Paste")
			(net "GND")
		)
		(pad "AU37" smd circle
			(at 11.400028 11.400028)
			(size 0.4572 0.4572)
			(layers "F.Cu" "F.Mask" "F.Paste")
			(net "GND")
		)
		(pad "AU38" smd circle
			(at 12.349988 11.400028)
			(size 0.4572 0.4572)
			(layers "F.Cu" "F.Mask" "F.Paste")
			(net "Net_5358")
		)
		(pad "AU39" smd circle
			(at 13.299948 11.400028)
			(size 0.4572 0.4572)
			(layers "F.Cu" "F.Mask" "F.Paste")
			(net "Net_5330")
		)
		(pad "AU40" smd circle
			(at 14.249908 11.400028)
			(size 0.4572 0.4572)
			(layers "F.Cu" "F.Mask" "F.Paste")
			(net "GND")
		)
		(pad "AU41" smd circle
			(at 15.200122 11.400028)
			(size 0.4572 0.4572)
			(layers "F.Cu" "F.Mask" "F.Paste")
			(net "GND")
		)
		(pad "AU42" smd circle
			(at 16.150082 11.400028)
			(size 0.4572 0.4572)
			(layers "F.Cu" "F.Mask" "F.Paste")
			(net "GND")
		)
		(pad "AU43" smd circle
			(at 17.100042 11.400028)
			(size 0.4572 0.4572)
			(layers "F.Cu" "F.Mask" "F.Paste")
			(net "P5E_PEX2_STN0_TX_DP<4>")
		)
		(pad "AU44" smd circle
			(at 18.050002 11.400028)
			(size 0.4572 0.4572)
			(layers "F.Cu" "F.Mask" "F.Paste")
			(net "P5E_PEX2_STN0_TX_DN<4>")
		)
		(pad "AU45" smd circle
			(at 18.999962 11.400028)
			(size 0.4572 0.4572)
			(layers "F.Cu" "F.Mask" "F.Paste")
			(net "GND")
		)
		(pad "AU46" smd circle
			(at 19.949922 11.400028)
			(size 0.4572 0.4572)
			(layers "F.Cu" "F.Mask" "F.Paste")
			(net "P5E_PEX2_STN0_RX_DP<4>")
		)
		(pad "AU47" smd circle
			(at 20.899882 11.400028)
			(size 0.4572 0.4572)
			(layers "F.Cu" "F.Mask" "F.Paste")
			(net "P5E_PEX2_STN0_RX_DN<4>")
		)
		(pad "AU48" smd circle
			(at 21.850096 11.400028)
			(size 0.4572 0.4572)
			(layers "F.Cu" "F.Mask" "F.Paste")
			(net "GND")
		)
		(pad "AU49" smd circle
			(at 22.800056 11.400028)
			(size 0.4572 0.4572)
			(layers "F.Cu" "F.Mask" "F.Paste")
			(net "GND")
		)
		(pad "AV1" smd circle
			(at -22.800056 12.349988)
			(size 0.4572 0.4572)
			(layers "F.Cu" "F.Mask" "F.Paste")
			(net "Net_1633")
		)
		(pad "AV2" smd circle
			(at -21.850096 12.349988)
			(size 0.4572 0.4572)
			(layers "F.Cu" "F.Mask" "F.Paste")
			(net "Net_1629")
		)
		(pad "AV3" smd circle
			(at -20.899882 12.349988)
			(size 0.4572 0.4572)
			(layers "F.Cu" "F.Mask" "F.Paste")
			(net "GND")
		)
		(pad "AV4" smd circle
			(at -19.949922 12.349988)
			(size 0.4572 0.4572)
			(layers "F.Cu" "F.Mask" "F.Paste")
			(net "GND")
		)
		(pad "AV5" smd circle
			(at -18.999962 12.349988)
			(size 0.4572 0.4572)
			(layers "F.Cu" "F.Mask" "F.Paste")
			(net "GND")
		)
		(pad "AV6" smd circle
			(at -18.050002 12.349988)
			(size 0.4572 0.4572)
			(layers "F.Cu" "F.Mask" "F.Paste")
			(net "GND")
		)
		(pad "AV7" smd circle
			(at -17.100042 12.349988)
			(size 0.4572 0.4572)
			(layers "F.Cu" "F.Mask" "F.Paste")
			(net "GND")
		)
		(pad "AV8" smd circle
			(at -16.150082 12.349988)
			(size 0.4572 0.4572)
			(layers "F.Cu" "F.Mask" "F.Paste")
			(net "Net_1449")
		)
		(pad "AV9" smd circle
			(at -15.200122 12.349988)
			(size 0.4572 0.4572)
			(layers "F.Cu" "F.Mask" "F.Paste")
			(net "Net_1368")
		)
		(pad "AV10" smd circle
			(at -14.249908 12.349988)
			(size 0.4572 0.4572)
			(layers "F.Cu" "F.Mask" "F.Paste")
			(net "GND")
		)
		(pad "AV11" smd circle
			(at -13.299948 12.349988)
			(size 0.4572 0.4572)
			(layers "F.Cu" "F.Mask" "F.Paste")
			(net "GND")
		)
		(pad "AV12" smd circle
			(at -12.349988 12.349988)
			(size 0.4572 0.4572)
			(layers "F.Cu" "F.Mask" "F.Paste")
			(net "Net_5348")
		)
		(pad "AV13" smd circle
			(at -11.400028 12.349988)
			(size 0.4572 0.4572)
			(layers "F.Cu" "F.Mask" "F.Paste")
			(net "Net_5349")
		)
		(pad "AV14" smd circle
			(at -10.450068 12.349988)
			(size 0.4572 0.4572)
			(layers "F.Cu" "F.Mask" "F.Paste")
			(net "Net_5340")
		)
		(pad "AV15" smd circle
			(at -9.500108 12.349988)
			(size 0.4572 0.4572)
			(layers "F.Cu" "F.Mask" "F.Paste")
			(net "Net_5334")
		)
		(pad "AV16" smd circle
			(at -8.549894 12.349988)
			(size 0.4572 0.4572)
			(layers "F.Cu" "F.Mask" "F.Paste")
			(net "Net_5343")
		)
		(pad "AV17" smd circle
			(at -7.599934 12.349988)
			(size 0.4572 0.4572)
			(layers "F.Cu" "F.Mask" "F.Paste")
			(net "Net_5344")
		)
		(pad "AV18" smd circle
			(at -6.649974 12.349988)
			(size 0.4572 0.4572)
			(layers "F.Cu" "F.Mask" "F.Paste")
			(net "Net_5339")
		)
		(pad "AV19" smd circle
			(at -5.700014 12.349988)
			(size 0.4572 0.4572)
			(layers "F.Cu" "F.Mask" "F.Paste")
			(net "Net_5335")
		)
		(pad "AV20" smd circle
			(at -4.750054 12.349988)
			(size 0.4572 0.4572)
			(layers "F.Cu" "F.Mask" "F.Paste")
			(net "GND")
		)
		(pad "AV21" smd circle
			(at -3.800094 12.349988)
			(size 0.4572 0.4572)
			(layers "F.Cu" "F.Mask" "F.Paste")
			(net "Net_5374")
		)
		(pad "AV22" smd circle
			(at -2.84988 12.349988)
			(size 0.4572 0.4572)
			(layers "F.Cu" "F.Mask" "F.Paste")
			(net "Net_5375")
		)
		(pad "AV23" smd circle
			(at -1.89992 12.349988)
			(size 0.4572 0.4572)
			(layers "F.Cu" "F.Mask" "F.Paste")
			(net "Net_5377")
		)
		(pad "AV24" smd circle
			(at -0.94996 12.349988)
			(size 0.4572 0.4572)
			(layers "F.Cu" "F.Mask" "F.Paste")
			(net "GND")
		)
		(pad "AV25" smd circle
			(at 0 12.349988)
			(size 0.4572 0.4572)
			(layers "F.Cu" "F.Mask" "F.Paste")
			(net "PEX2_MODE_SEL2")
		)
		(pad "AV26" smd circle
			(at 0.94996 12.349988)
			(size 0.4572 0.4572)
			(layers "F.Cu" "F.Mask" "F.Paste")
			(net "PEX2_MODE_SEL7")
		)
		(pad "AV27" smd circle
			(at 1.89992 12.349988)
			(size 0.4572 0.4572)
			(layers "F.Cu" "F.Mask" "F.Paste")
			(net "PEX2_MODE_SEL3")
		)
		(pad "AV28" smd circle
			(at 2.84988 12.349988)
			(size 0.4572 0.4572)
			(layers "F.Cu" "F.Mask" "F.Paste")
			(net "PEX2_MODE_SEL9")
		)
		(pad "AV29" smd circle
			(at 3.800094 12.349988)
			(size 0.4572 0.4572)
			(layers "F.Cu" "F.Mask" "F.Paste")
			(net "PEX2_PCA9555_INT_R_N")
		)
		(pad "AV30" smd circle
			(at 4.750054 12.349988)
			(size 0.4572 0.4572)
			(layers "F.Cu" "F.Mask" "F.Paste")
			(net "PEX2_SYS_ERR_N")
		)
		(pad "AV31" smd circle
			(at 5.700014 12.349988)
			(size 0.4572 0.4572)
			(layers "F.Cu" "F.Mask" "F.Paste")
			(net "PEX2_MODE_SEL6")
		)
		(pad "AV32" smd circle
			(at 6.649974 12.349988)
			(size 0.4572 0.4572)
			(layers "F.Cu" "F.Mask" "F.Paste")
			(net "PEX2_MODE_SEL10")
		)
		(pad "AV33" smd circle
			(at 7.599934 12.349988)
			(size 0.4572 0.4572)
			(layers "F.Cu" "F.Mask" "F.Paste")
			(net "Net_5352")
		)
		(pad "AV34" smd circle
			(at 8.549894 12.349988)
			(size 0.4572 0.4572)
			(layers "F.Cu" "F.Mask" "F.Paste")
			(net "Net_5325")
		)
		(pad "AV35" smd circle
			(at 9.500108 12.349988)
			(size 0.4572 0.4572)
			(layers "F.Cu" "F.Mask" "F.Paste")
			(net "Net_5354")
		)
		(pad "AV36" smd circle
			(at 10.450068 12.349988)
			(size 0.4572 0.4572)
			(layers "F.Cu" "F.Mask" "F.Paste")
			(net "Net_5331")
		)
		(pad "AV37" smd circle
			(at 11.400028 12.349988)
			(size 0.4572 0.4572)
			(layers "F.Cu" "F.Mask" "F.Paste")
			(net "Net_5356")
		)
		(pad "AV38" smd circle
			(at 12.349988 12.349988)
			(size 0.4572 0.4572)
			(layers "F.Cu" "F.Mask" "F.Paste")
			(net "Net_5355")
		)
		(pad "AV39" smd circle
			(at 13.299948 12.349988)
			(size 0.4572 0.4572)
			(layers "F.Cu" "F.Mask" "F.Paste")
			(net "Net_5347")
		)
		(pad "AV40" smd circle
			(at 14.249908 12.349988)
			(size 0.4572 0.4572)
			(layers "F.Cu" "F.Mask" "F.Paste")
			(net "GND")
		)
		(pad "AV41" smd circle
			(at 15.200122 12.349988)
			(size 0.4572 0.4572)
			(layers "F.Cu" "F.Mask" "F.Paste")
			(net "P5E_PEX2_STN0_TX_DP<5>")
		)
		(pad "AV42" smd circle
			(at 16.150082 12.349988)
			(size 0.4572 0.4572)
			(layers "F.Cu" "F.Mask" "F.Paste")
			(net "P5E_PEX2_STN0_TX_DN<5>")
		)
		(pad "AV43" smd circle
			(at 17.100042 12.349988)
			(size 0.4572 0.4572)
			(layers "F.Cu" "F.Mask" "F.Paste")
			(net "GND")
		)
		(pad "AV44" smd circle
			(at 18.050002 12.349988)
			(size 0.4572 0.4572)
			(layers "F.Cu" "F.Mask" "F.Paste")
			(net "GND")
		)
		(pad "AV45" smd circle
			(at 18.999962 12.349988)
			(size 0.4572 0.4572)
			(layers "F.Cu" "F.Mask" "F.Paste")
			(net "GND")
		)
		(pad "AV46" smd circle
			(at 19.949922 12.349988)
			(size 0.4572 0.4572)
			(layers "F.Cu" "F.Mask" "F.Paste")
			(net "GND")
		)
		(pad "AV47" smd circle
			(at 20.899882 12.349988)
			(size 0.4572 0.4572)
			(layers "F.Cu" "F.Mask" "F.Paste")
			(net "GND")
		)
		(pad "AV48" smd circle
			(at 21.850096 12.349988)
			(size 0.4572 0.4572)
			(layers "F.Cu" "F.Mask" "F.Paste")
			(net "P5E_PEX2_STN0_RX_DP<5>")
		)
		(pad "AV49" smd circle
			(at 22.800056 12.349988)
			(size 0.4572 0.4572)
			(layers "F.Cu" "F.Mask" "F.Paste")
			(net "P5E_PEX2_STN0_RX_DN<5>")
		)
		(pad "AW1" smd circle
			(at -22.800056 13.299948)
			(size 0.4572 0.4572)
			(layers "F.Cu" "F.Mask" "F.Paste")
			(net "GND")
		)
		(pad "AW2" smd circle
			(at -21.850096 13.299948)
			(size 0.4572 0.4572)
			(layers "F.Cu" "F.Mask" "F.Paste")
			(net "GND")
		)
		(pad "AW3" smd circle
			(at -20.899882 13.299948)
			(size 0.4572 0.4572)
			(layers "F.Cu" "F.Mask" "F.Paste")
			(net "Net_1605")
		)
		(pad "AW4" smd circle
			(at -19.949922 13.299948)
			(size 0.4572 0.4572)
			(layers "F.Cu" "F.Mask" "F.Paste")
			(net "Net_1623")
		)
		(pad "AW5" smd circle
			(at -18.999962 13.299948)
			(size 0.4572 0.4572)
			(layers "F.Cu" "F.Mask" "F.Paste")
			(net "GND")
		)
		(pad "AW6" smd circle
			(at -18.050002 13.299948)
			(size 0.4572 0.4572)
			(layers "F.Cu" "F.Mask" "F.Paste")
			(net "Net_1355")
		)
		(pad "AW7" smd circle
			(at -17.100042 13.299948)
			(size 0.4572 0.4572)
			(layers "F.Cu" "F.Mask" "F.Paste")
			(net "Net_1720")
		)
		(pad "AW8" smd circle
			(at -16.150082 13.299948)
			(size 0.4572 0.4572)
			(layers "F.Cu" "F.Mask" "F.Paste")
			(net "GND")
		)
		(pad "AW9" smd circle
			(at -15.200122 13.299948)
			(size 0.4572 0.4572)
			(layers "F.Cu" "F.Mask" "F.Paste")
			(net "GND")
		)
		(pad "AW10" smd circle
			(at -14.249908 13.299948)
			(size 0.4572 0.4572)
			(layers "F.Cu" "F.Mask" "F.Paste")
			(net "GND")
		)
		(pad "AW11" smd circle
			(at -13.299948 13.299948)
			(size 0.4572 0.4572)
			(layers "F.Cu" "F.Mask" "F.Paste")
			(net "GND")
		)
		(pad "AW12" smd circle
			(at -12.349988 13.299948)
			(size 0.4572 0.4572)
			(layers "F.Cu" "F.Mask" "F.Paste")
			(net "Net_5346")
		)
		(pad "AW13" smd circle
			(at -11.400028 13.299948)
			(size 0.4572 0.4572)
			(layers "F.Cu" "F.Mask" "F.Paste")
			(net "Net_5342")
		)
		(pad "AW14" smd circle
			(at -10.450068 13.299948)
			(size 0.4572 0.4572)
			(layers "F.Cu" "F.Mask" "F.Paste")
			(net "Net_5338")
		)
		(pad "AW15" smd circle
			(at -9.500108 13.299948)
			(size 0.4572 0.4572)
			(layers "F.Cu" "F.Mask" "F.Paste")
			(net "Net_5333")
		)
		(pad "AW16" smd circle
			(at -8.549894 13.299948)
			(size 0.4572 0.4572)
			(layers "F.Cu" "F.Mask" "F.Paste")
			(net "Net_5345")
		)
		(pad "AW17" smd circle
			(at -7.599934 13.299948)
			(size 0.4572 0.4572)
			(layers "F.Cu" "F.Mask" "F.Paste")
			(net "Net_5341")
		)
		(pad "AW18" smd circle
			(at -6.649974 13.299948)
			(size 0.4572 0.4572)
			(layers "F.Cu" "F.Mask" "F.Paste")
			(net "Net_5337")
		)
		(pad "AW19" smd circle
			(at -5.700014 13.299948)
			(size 0.4572 0.4572)
			(layers "F.Cu" "F.Mask" "F.Paste")
			(net "Net_5332")
		)
		(pad "AW20" smd circle
			(at -4.750054 13.299948)
			(size 0.4572 0.4572)
			(layers "F.Cu" "F.Mask" "F.Paste")
			(net "GND")
		)
		(pad "AW21" smd circle
			(at -3.800094 13.299948)
			(size 0.4572 0.4572)
			(layers "F.Cu" "F.Mask" "F.Paste")
			(net "Net_5366")
		)
		(pad "AW22" smd circle
			(at -2.84988 13.299948)
			(size 0.4572 0.4572)
			(layers "F.Cu" "F.Mask" "F.Paste")
			(net "Net_5376")
		)
		(pad "AW23" smd circle
			(at -1.89992 13.299948)
			(size 0.4572 0.4572)
			(layers "F.Cu" "F.Mask" "F.Paste")
			(net "Net_5365")
		)
		(pad "AW24" smd circle
			(at -0.94996 13.299948)
			(size 0.4572 0.4572)
			(layers "F.Cu" "F.Mask" "F.Paste")
			(net "GND")
		)
		(pad "AW25" smd circle
			(at 0 13.299948)
			(size 0.4572 0.4572)
			(layers "F.Cu" "F.Mask" "F.Paste")
			(net "PEX2_MODE_SEL5")
		)
		(pad "AW26" smd circle
			(at 0.94996 13.299948)
			(size 0.4572 0.4572)
			(layers "F.Cu" "F.Mask" "F.Paste")
			(net "PEX2_DBG_MODE3")
		)
		(pad "AW27" smd circle
			(at 1.89992 13.299948)
			(size 0.4572 0.4572)
			(layers "F.Cu" "F.Mask" "F.Paste")
			(net "PEX2_MODE_SEL0")
		)
	)
)
